(kicad_pcb
	(version 20241229)
	(generator "pcbnew")
	(generator_version "9.0")
	(general
		(thickness 1.6296)
		(legacy_teardrops no)
	)
	(paper "A3")
	(title_block
		(title "Thunderbolt to 10GbE adapter")
		(date "2026-04-21")
		(rev "1.1.0")
		(company "Antmicro Ltd")
		(comment 1 "www.antmicro.com")
		(comment 9 "footprints 54-58 of 703")
	)
	(layers
		(0 "F.Cu" signal)
		(4 "In1.Cu" signal)
		(6 "In2.Cu" signal)
		(8 "In3.Cu" signal)
		(10 "In4.Cu" signal)
		(12 "In5.Cu" signal)
		(14 "In6.Cu" signal)
		(2 "B.Cu" signal)
		(9 "F.Adhes" user "F.Adhesive")
		(11 "B.Adhes" user "B.Adhesive")
		(13 "F.Paste" user)
		(15 "B.Paste" user)
		(5 "F.SilkS" user "F.Silkscreen")
		(7 "B.SilkS" user "B.Silkscreen")
		(1 "F.Mask" user)
		(3 "B.Mask" user)
		(17 "Dwgs.User" user "User.Drawings")
		(19 "Cmts.User" user "User.Comments")
		(21 "Eco1.User" user "User.Eco1")
		(23 "Eco2.User" user "User.Eco2")
		(25 "Edge.Cuts" user)
		(27 "Margin" user)
		(31 "F.CrtYd" user "F.Courtyard")
		(29 "B.CrtYd" user "B.Courtyard")
		(35 "F.Fab" user)
		(33 "B.Fab" user)
	)
	(footprint "antmicro-footprints:C_0603_1608Metric_EIA"
		(layer "F.Cu")
		(at 166.505 99.224999 -90)
		(descr "Capacitor SMD 0603, IPC-7351 Density Level A")
		(tags "Capacitor 0603")
		(property "Reference" "C156"
			(at 0 -7.695 270)
			(layer "F.SilkS")
			(effects
				(font
					(size 0.7 0.7)
					(thickness 0.15)
				)
			)
		)
		(property "Value" "C_22u_16V_0603"
			(at -1.42757 1.770288 270)
			(layer "F.Fab")
			(effects
				(font
					(size 0.7 0.7)
					(thickness 0.15)
				)
				(justify left bottom)
			)
		)
		(property "Datasheet" "https://product.samsungsem.com/mlcc/CL10A226MO7JZN.do"
			(at 0 0 270)
			(layer "F.Fab")
			(hide yes)
			(effects
				(font
					(size 1.27 1.27)
					(thickness 0.15)
				)
			)
		)
		(property "Description" "SMD Multilayer Ceramic Capacitor"
			(at 0 0 270)
			(layer "F.Fab")
			(hide yes)
			(effects
				(font
					(size 1.27 1.27)
					(thickness 0.15)
				)
			)
		)
		(property "MPN" "CL10A226MO7JZNC"
			(at 0 0 270)
			(unlocked yes)
			(layer "F.Fab")
			(hide yes)
			(effects
				(font
					(size 1 1)
					(thickness 0.15)
				)
			)
		)
		(property "Manufacturer" "Samsung Electro-Mechanics"
			(at 0 0 270)
			(unlocked yes)
			(layer "F.Fab")
			(hide yes)
			(effects
				(font
					(size 1 1)
					(thickness 0.15)
				)
			)
		)
		(property "License" "Apache-2.0"
			(at 0 0 270)
			(unlocked yes)
			(layer "F.Fab")
			(hide yes)
			(effects
				(font
					(size 1 1)
					(thickness 0.15)
				)
			)
		)
		(property "Author" "Antmicro"
			(at 0 0 270)
			(unlocked yes)
			(layer "F.Fab")
			(hide yes)
			(effects
				(font
					(size 1 1)
					(thickness 0.15)
				)
			)
		)
		(property "Val" "22u"
			(at 0 0 270)
			(unlocked yes)
			(layer "F.Fab")
			(hide yes)
			(effects
				(font
					(size 1 1)
					(thickness 0.15)
				)
			)
		)
		(property "Voltage" "16V"
			(at 0 0 270)
			(unlocked yes)
			(layer "F.Fab")
			(hide yes)
			(effects
				(font
					(size 1 1)
					(thickness 0.15)
				)
			)
		)
		(property "Dielectric" ""
			(at 0 0 270)
			(unlocked yes)
			(layer "F.Fab")
			(hide yes)
			(effects
				(font
					(size 1 1)
					(thickness 0.15)
				)
			)
		)
		(sheetname "/X710-AT2 power/")
		(sheetfile "x710-at2-power.kicad_sch")
		(attr smd)
		(fp_line
			(start -0.15 0.55)
			(end 0.15 0.55)
			(stroke
				(width 0.15)
				(type solid)
			)
			(layer "F.SilkS")
		)
		(fp_line
			(start -0.15 -0.55)
			(end 0.15 -0.55)
			(stroke
				(width 0.15)
				(type solid)
			)
			(layer "F.SilkS")
		)
		(fp_rect
			(start -1.25 -0.65)
			(end 1.25 0.65)
			(stroke
				(width 0.05)
				(type solid)
			)
			(fill no)
			(layer "F.CrtYd")
		)
		(fp_rect
			(start -0.8 -0.45)
			(end 0.8 0.45)
			(stroke
				(width 0.15)
				(type solid)
			)
			(fill no)
			(layer "F.Fab")
		)
		(fp_text user "License: Apache-2.0"
			(at -1.682 5.895 270)
			(layer "F.Fab")
			(effects
				(font
					(size 0.7 0.7)
					(thickness 0.15)
				)
				(justify left bottom)
			)
		)
		(fp_text user "${REFERENCE}"
			(at -1.682 3.895 270)
			(layer "F.Fab")
			(effects
				(font
					(size 0.7 0.7)
					(thickness 0.15)
				)
				(justify left bottom)
			)
		)
		(fp_text user "Author: Antmicro"
			(at -1.682 4.894 270)
			(layer "F.Fab")
			(effects
				(font
					(size 0.7 0.7)
					(thickness 0.15)
				)
				(justify left bottom)
			)
		)
		(pad "1" smd roundrect
			(at -0.7 0 270)
			(size 0.8 1.1)
			(layers "F.Cu" "F.Mask" "F.Paste")
			(roundrect_rratio 0.2)
			(net 23 "GND")
			(pintype "passive")
		)
		(pad "2" smd roundrect
			(at 0.7 0 270)
			(size 0.8 1.1)
			(layers "F.Cu" "F.Mask" "F.Paste")
			(roundrect_rratio 0.2)
			(net 136 "+1V0")
			(pintype "passive")
		)
	)
	(footprint "antmicro-footprints:R_0402_1005Metric"
		(layer "F.Cu")
		(at 136.149999 110.149999 180)
		(descr "Resistor SMD 0402")
		(tags "resistor SMD 0402")
		(property "Reference" "R100"
			(at -16.549997 -17.25 180)
			(layer "F.SilkS")
			(effects
				(font
					(size 0.7 0.7)
					(thickness 0.15)
				)
			)
		)
		(property "Value" "R_16k_0402"
			(at -1.011843 1.772047 180)
			(layer "F.Fab")
			(effects
				(font
					(size 0.7 0.7)
					(thickness 0.15)
				)
				(justify left bottom)
			)
		)
		(property "Datasheet" "https://www.bourns.com/docs/product-datasheets/cr.pdf"
			(at 0 0 180)
			(layer "F.Fab")
			(hide yes)
			(effects
				(font
					(size 1.27 1.27)
					(thickness 0.15)
				)
			)
		)
		(property "Description" "SMD Chip Resistor"
			(at 0 0 180)
			(layer "F.Fab")
			(hide yes)
			(effects
				(font
					(size 1.27 1.27)
					(thickness 0.15)
				)
			)
		)
		(property "MPN" "CR0402-FX-1602GLF"
			(at 0 0 180)
			(unlocked yes)
			(layer "F.Fab")
			(hide yes)
			(effects
				(font
					(size 1 1)
					(thickness 0.15)
				)
			)
		)
		(property "Manufacturer" "Bourns"
			(at 0 0 180)
			(unlocked yes)
			(layer "F.Fab")
			(hide yes)
			(effects
				(font
					(size 1 1)
					(thickness 0.15)
				)
			)
		)
		(property "License" "Apache-2.0"
			(at 0 0 180)
			(unlocked yes)
			(layer "F.Fab")
			(hide yes)
			(effects
				(font
					(size 1 1)
					(thickness 0.15)
				)
			)
		)
		(property "Author" "Antmicro"
			(at 0 0 180)
			(unlocked yes)
			(layer "F.Fab")
			(hide yes)
			(effects
				(font
					(size 1 1)
					(thickness 0.15)
				)
			)
		)
		(property "Val" "16k"
			(at 0 0 180)
			(unlocked yes)
			(layer "F.Fab")
			(hide yes)
			(effects
				(font
					(size 1 1)
					(thickness 0.15)
				)
			)
		)
		(property "Tolerance" "1%"
			(at 0 0 180)
			(unlocked yes)
			(layer "F.Fab")
			(hide yes)
			(effects
				(font
					(size 1 1)
					(thickness 0.15)
				)
			)
		)
		(sheetname "/X710 DCDC converters/")
		(sheetfile "DCDC_converters_X710.kicad_sch")
		(attr smd)
		(fp_rect
			(start -0.925 -0.47)
			(end 0.925 0.47)
			(stroke
				(width 0.05)
				(type default)
			)
			(fill no)
			(layer "F.CrtYd")
		)
		(fp_rect
			(start -0.5 -0.25)
			(end 0.5 0.25)
			(stroke
				(width 0.15)
				(type solid)
			)
			(fill no)
			(layer "F.Fab")
		)
		(fp_text user "${REFERENCE}"
			(at -0.95 3.168 180)
			(layer "F.Fab")
			(effects
				(font
					(size 0.7 0.7)
					(thickness 0.15)
				)
				(justify left bottom)
			)
		)
		(fp_text user "License: Apache-2.0"
			(at -0.95 5.169 180)
			(layer "F.Fab")
			(effects
				(font
					(size 0.7 0.7)
					(thickness 0.15)
				)
				(justify left bottom)
			)
		)
		(fp_text user "Author: Antmicro"
			(at -0.95 4.169 180)
			(layer "F.Fab")
			(effects
				(font
					(size 0.7 0.7)
					(thickness 0.15)
				)
				(justify left bottom)
			)
		)
		(pad "1" smd roundrect
			(at -0.48 0 180)
			(size 0.59 0.64)
			(layers "F.Cu" "F.Mask" "F.Paste")
			(roundrect_rratio 0.25)
			(net 336 "/X710 DCDC converters/VCCD_FB")
			(pintype "passive")
		)
		(pad "2" smd roundrect
			(at 0.48 0 180)
			(size 0.59 0.64)
			(layers "F.Cu" "F.Mask" "F.Paste")
			(roundrect_rratio 0.25)
			(net 335 "/X710 DCDC converters/+VCCD_OUT")
			(pintype "passive")
		)
	)
	(footprint "antmicro-footprints:C_0402_1005Metric"
		(layer "F.Cu")
		(at 134.2 60.4)
		(descr "Capacitor SMD 0402")
		(tags "capacitor SMD 0402")
		(property "Reference" "C323"
			(at -3.8 0.4 0)
			(layer "F.SilkS")
			(effects
				(font
					(size 0.7 0.7)
					(thickness 0.15)
				)
				(justify left bottom)
			)
		)
		(property "Value" "C_1u_25V_0402"
			(at -1.022927 2.155213 0)
			(layer "F.Fab")
			(effects
				(font
					(size 0.7 0.7)
					(thickness 0.15)
				)
				(justify left bottom)
			)
		)
		(property "Datasheet" "https://www.murata.com/products/productdetail?partno=GRM155R61E105KE11%23"
			(at 0 0 0)
			(layer "F.Fab")
			(hide yes)
			(effects
				(font
					(size 1.27 1.27)
					(thickness 0.15)
				)
			)
		)
		(property "Description" "SMD Multilayer Ceramic Capacitor, 1 µF, 25 V, 0402 [1005 Metric], ± 10%, X5R, GRM Series"
			(at 0 0 0)
			(layer "F.Fab")
			(hide yes)
			(effects
				(font
					(size 1.27 1.27)
					(thickness 0.15)
				)
			)
		)
		(property "MPN" "GRM155R61E105KE11J"
			(at 0 0 0)
			(unlocked yes)
			(layer "F.Fab")
			(hide yes)
			(effects
				(font
					(size 1 1)
					(thickness 0.15)
				)
			)
		)
		(property "Manufacturer" "Murata"
			(at 0 0 0)
			(unlocked yes)
			(layer "F.Fab")
			(hide yes)
			(effects
				(font
					(size 1 1)
					(thickness 0.15)
				)
			)
		)
		(property "License" "Apache-2.0"
			(at 0 0 0)
			(unlocked yes)
			(layer "F.Fab")
			(hide yes)
			(effects
				(font
					(size 1 1)
					(thickness 0.15)
				)
			)
		)
		(property "Author" "Antmicro"
			(at 0 0 0)
			(unlocked yes)
			(layer "F.Fab")
			(hide yes)
			(effects
				(font
					(size 1 1)
					(thickness 0.15)
				)
			)
		)
		(property "Val" "1u"
			(at 0 0 0)
			(unlocked yes)
			(layer "F.Fab")
			(hide yes)
			(effects
				(font
					(size 1 1)
					(thickness 0.15)
				)
			)
		)
		(property "Voltage" "25V"
			(at 0 0 0)
			(unlocked yes)
			(layer "F.Fab")
			(hide yes)
			(effects
				(font
					(size 1 1)
					(thickness 0.15)
				)
			)
		)
		(property "Dielectric" "X5R"
			(at 0 0 0)
			(unlocked yes)
			(layer "F.Fab")
			(hide yes)
			(effects
				(font
					(size 1 1)
					(thickness 0.15)
				)
			)
		)
		(sheetname "/Power input/")
		(sheetfile "power_input.kicad_sch")
		(attr smd)
		(fp_rect
			(start -0.925 -0.47)
			(end 0.925 0.47)
			(stroke
				(width 0.05)
				(type default)
			)
			(fill no)
			(layer "F.CrtYd")
		)
		(fp_line
			(start -0.494 -0.25)
			(end 0.504 -0.25)
			(stroke
				(width 0.15)
				(type solid)
			)
			(layer "F.Fab")
		)
		(fp_line
			(start -0.494 0.248)
			(end -0.494 -0.25)
			(stroke
				(width 0.15)
				(type solid)
			)
			(layer "F.Fab")
		)
		(fp_line
			(start 0.504 -0.25)
			(end 0.504 0.248)
			(stroke
				(width 0.15)
				(type solid)
			)
			(layer "F.Fab")
		)
		(fp_line
			(start 0.504 0.248)
			(end -0.494 0.248)
			(stroke
				(width 0.15)
				(type solid)
			)
			(layer "F.Fab")
		)
		(fp_text user "Author: Antmicro"
			(at -0.939 3.399 0)
			(layer "F.Fab")
			(effects
				(font
					(size 0.7 0.7)
					(thickness 0.15)
				)
				(justify left bottom)
			)
		)
		(fp_text user "License: Apache-2.0"
			(at -0.939 5.799 0)
			(layer "F.Fab")
			(effects
				(font
					(size 0.7 0.7)
					(thickness 0.15)
				)
				(justify left bottom)
			)
		)
		(fp_text user "${REFERENCE}"
			(at -0.939 4.599 0)
			(layer "F.Fab")
			(effects
				(font
					(size 0.7 0.7)
					(thickness 0.15)
				)
				(justify left bottom)
			)
		)
		(pad "1" smd roundrect
			(at -0.48 0)
			(size 0.59 0.64)
			(layers "F.Cu" "F.Mask" "F.Paste")
			(roundrect_rratio 0.25)
			(net 23 "GND")
			(pintype "passive")
		)
		(pad "2" smd roundrect
			(at 0.48 0)
			(size 0.59 0.64)
			(layers "F.Cu" "F.Mask" "F.Paste")
			(roundrect_rratio 0.25)
			(net 40 "+5V")
			(pintype "passive")
		)
	)
	(footprint "antmicro-footprints:VQFN-HR-9_2x1.5mm"
		(layer "F.Cu")
		(at 133.950001 95.799998 -90)
		(property "Reference" "U9"
			(at -9.199999 -36.934999 270)
			(layer "F.SilkS")
			(effects
				(font
					(size 0.7 0.7)
					(thickness 0.15)
				)
			)
		)
		(property "Value" "TPS566231P"
			(at -1.65 2.15 270)
			(layer "F.Fab")
			(effects
				(font
					(size 0.7 0.7)
					(thickness 0.15)
				)
				(justify left bottom)
			)
		)
		(property "Datasheet" "https://www.ti.com/lit/ds/symlink/tps566231.pdf"
			(at 0 -0.045 270)
			(layer "F.Fab")
			(effects
				(font
					(size 0.7 0.7)
					(thickness 0.15)
				)
				(justify left bottom)
			)
		)
		(property "Description" "Switching Voltage Regulators 3-V to 18-V, 6-A synchronous buck converter"
			(at -1.45 3.65 270)
			(layer "F.Fab")
			(effects
				(font
					(size 0.7 0.7)
					(thickness 0.15)
				)
				(justify left bottom)
			)
		)
		(property "Manufacturer" "Texas Instruments"
			(at 0 0 270)
			(unlocked yes)
			(layer "F.Fab")
			(hide yes)
			(effects
				(font
					(size 1 1)
					(thickness 0.15)
				)
			)
		)
		(property "MPN" "TPS566231PRQFR"
			(at 0 0 270)
			(unlocked yes)
			(layer "F.Fab")
			(hide yes)
			(effects
				(font
					(size 1 1)
					(thickness 0.15)
				)
			)
		)
		(property "Author" "Antmicro"
			(at 0 0 270)
			(unlocked yes)
			(layer "F.Fab")
			(hide yes)
			(effects
				(font
					(size 1 1)
					(thickness 0.15)
				)
			)
		)
		(property "License" "Apache-2.0"
			(at 0 0 270)
			(unlocked yes)
			(layer "F.Fab")
			(hide yes)
			(effects
				(font
					(size 1 1)
					(thickness 0.15)
				)
			)
		)
		(sheetname "/X710 DCDC converters/")
		(sheetfile "DCDC_converters_X710.kicad_sch")
		(attr smd)
		(fp_line
			(start -1 0.945)
			(end -0.695 0.945)
			(stroke
				(width 0.15)
				(type solid)
			)
			(layer "F.SilkS")
		)
		(fp_line
			(start 1 0.945)
			(end 0.2 0.945)
			(stroke
				(width 0.15)
				(type solid)
			)
			(layer "F.SilkS")
		)
		(fp_line
			(start -1 -0.945)
			(end -0.695 -0.945)
			(stroke
				(width 0.15)
				(type solid)
			)
			(layer "F.SilkS")
		)
		(fp_line
			(start 1 -0.945)
			(end 0.695 -0.945)
			(stroke
				(width 0.15)
				(type solid)
			)
			(layer "F.SilkS")
		)
		(fp_circle
			(center -1.18 -0.77)
			(end -1.13 -0.77)
			(stroke
				(width 0.15)
				(type solid)
			)
			(fill yes)
			(layer "F.SilkS")
		)
		(fp_rect
			(start -1.3 -1.05)
			(end 1.3 1.05)
			(stroke
				(width 0.05)
				(type solid)
			)
			(fill no)
			(layer "F.CrtYd")
		)
		(fp_rect
			(start -1 -0.75)
			(end 1 0.75)
			(stroke
				(width 0.15)
				(type solid)
			)
			(fill no)
			(layer "F.Fab")
		)
		(fp_text user "License: Apache-2.0"
			(at -1.65 5.75 270)
			(layer "F.Fab")
			(effects
				(font
					(size 0.7 0.7)
					(thickness 0.15)
				)
				(justify left bottom)
			)
		)
		(fp_text user "Author: Antmicro"
			(at -1.65 4.55 270)
			(layer "F.Fab")
			(effects
				(font
					(size 0.7 0.7)
					(thickness 0.15)
				)
				(justify left bottom)
			)
		)
		(fp_text user "${REFERENCE}"
			(at -1.65 3.35 270)
			(layer "F.Fab")
			(effects
				(font
					(size 0.7 0.7)
					(thickness 0.15)
				)
				(justify left bottom)
			)
		)
		(pad "1" smd roundrect
			(at -0.925 -0.5 270)
			(size 0.55 0.25)
			(layers "F.Cu" "F.Mask" "F.Paste")
			(roundrect_rratio 0.125)
			(net 80 "/X710 DCDC converters/3V3_VCC")
			(pinfunction "V_{CC}")
			(pintype "passive")
		)
		(pad "2" smd roundrect
			(at -0.925 0 270)
			(size 0.55 0.25)
			(layers "F.Cu" "F.Mask" "F.Paste")
			(roundrect_rratio 0.125)
			(net 333 "/X710 DCDC converters/3V3_FB")
			(pinfunction "FB")
			(pintype "input")
		)
		(pad "3" smd roundrect
			(at -0.925 0.5 270)
			(size 0.55 0.25)
			(layers "F.Cu" "F.Mask" "F.Paste")
			(roundrect_rratio 0.125)
			(net 356 "/TB Controller - Power/0P9_BUFFERED")
			(pinfunction "EN")
			(pintype "input")
		)
		(pad "4" smd roundrect
			(at -0.25 0.45 270)
			(size 0.25 1)
			(layers "F.Cu" "F.Mask" "F.Paste")
			(roundrect_rratio 0.125)
			(net 23 "GND")
			(pinfunction "PGND")
			(pintype "power_in")
		)
		(pad "5" smd roundrect
			(at 0.925 0.5 270)
			(size 0.55 0.25)
			(layers "F.Cu" "F.Mask" "F.Paste")
			(roundrect_rratio 0.125)
			(net 40 "+5V")
			(pinfunction "V_{IN}")
			(pintype "power_in")
		)
		(pad "6" smd roundrect
			(at 0.925 0 270)
			(size 0.55 0.25)
			(layers "F.Cu" "F.Mask" "F.Paste")
			(roundrect_rratio 0.125)
			(net 40 "+5V")
			(pinfunction "V_{IN}")
			(pintype "passive")
		)
		(pad "7" smd roundrect
			(at 0.925 -0.5 270)
			(size 0.55 0.25)
			(layers "F.Cu" "F.Mask" "F.Paste")
			(roundrect_rratio 0.125)
			(net 118 "/X710 DCDC converters/3V3_BST")
			(pinfunction "BST")
			(pintype "passive")
		)
		(pad "8" smd roundrect
			(at 0.25 -0.3 270)
			(size 0.25 1.3)
			(layers "F.Cu" "F.Mask" "F.Paste")
			(roundrect_rratio 0.125)
			(net 117 "/X710 DCDC converters/3V3_SW")
			(pinfunction "SW")
			(pintype "power_out")
		)
		(pad "9" smd roundrect
			(at -0.25 -0.675 270)
			(size 0.25 0.55)
			(layers "F.Cu" "F.Mask" "F.Paste")
			(roundrect_rratio 0.125)
			(net 378 "/X710 DCDC converters/3V3_PG")
			(pinfunction "PG")
			(pintype "passive")
		)
	)
	(footprint "antmicro-footprints:R_0402_1005Metric"
		(layer "F.Cu")
		(at 158.105 65.174999 -90)
		(descr "Resistor SMD 0402")
		(tags "resistor SMD 0402")
		(property "Reference" "R156"
			(at -2.374999 -0.095001 270)
			(layer "F.SilkS")
			(effects
				(font
					(size 0.7 0.7)
					(thickness 0.15)
				)
			)
		)
		(property "Value" "R_100k_0402"
			(at -1.011843 1.772047 270)
			(layer "F.Fab")
			(effects
				(font
					(size 0.7 0.7)
					(thickness 0.15)
				)
				(justify left bottom)
			)
		)
		(property "Datasheet" "https://www.bourns.com/docs/product-datasheets/cr.pdf"
			(at 0 0 270)
			(layer "F.Fab")
			(hide yes)
			(effects
				(font
					(size 1.27 1.27)
					(thickness 0.15)
				)
			)
		)
		(property "Description" "SMD Chip Resistor, 100 kohm, ± 1%, 62.5 mW, 0402 [1005 Metric], Thick Film, General Purpose"
			(at 0 0 270)
			(layer "F.Fab")
			(hide yes)
			(effects
				(font
					(size 1.27 1.27)
					(thickness 0.15)
				)
			)
		)
		(property "MPN" "CR0402-FX-1003GLF"
			(at 0 0 270)
			(unlocked yes)
			(layer "F.Fab")
			(hide yes)
			(effects
				(font
					(size 1 1)
					(thickness 0.15)
				)
			)
		)
		(property "Manufacturer" "Bourns"
			(at 0 0 270)
			(unlocked yes)
			(layer "F.Fab")
			(hide yes)
			(effects
				(font
					(size 1 1)
					(thickness 0.15)
				)
			)
		)
		(property "License" "Apache-2.0"
			(at 0 0 270)
			(unlocked yes)
			(layer "F.Fab")
			(hide yes)
			(effects
				(font
					(size 1 1)
					(thickness 0.15)
				)
			)
		)
		(property "Author" "Antmicro"
			(at 0 0 270)
			(unlocked yes)
			(layer "F.Fab")
			(hide yes)
			(effects
				(font
					(size 1 1)
					(thickness 0.15)
				)
			)
		)
		(property "Val" "100k"
			(at 0 0 270)
			(unlocked yes)
			(layer "F.Fab")
			(hide yes)
			(effects
				(font
					(size 1 1)
					(thickness 0.15)
				)
			)
		)
		(property "Tolerance" "1%"
			(at 0 0 270)
			(unlocked yes)
			(layer "F.Fab")
			(hide yes)
			(effects
				(font
					(size 1 1)
					(thickness 0.15)
				)
			)
		)
		(sheetname "/X710-AT2 Misc/")
		(sheetfile "x710-at2-mics.kicad_sch")
		(attr smd)
		(fp_rect
			(start -0.925 -0.47)
			(end 0.925 0.47)
			(stroke
				(width 0.05)
				(type default)
			)
			(fill no)
			(layer "F.CrtYd")
		)
		(fp_rect
			(start -0.5 -0.25)
			(end 0.5 0.25)
			(stroke
				(width 0.15)
				(type solid)
			)
			(fill no)
			(layer "F.Fab")
		)
		(fp_text user "${REFERENCE}"
			(at -0.95 3.168 270)
			(layer "F.Fab")
			(effects
				(font
					(size 0.7 0.7)
					(thickness 0.15)
				)
				(justify left bottom)
			)
		)
		(fp_text user "License: Apache-2.0"
			(at -0.95 5.169 270)
			(layer "F.Fab")
			(effects
				(font
					(size 0.7 0.7)
					(thickness 0.15)
				)
				(justify left bottom)
			)
		)
		(fp_text user "Author: Antmicro"
			(at -0.95 4.169 270)
			(layer "F.Fab")
			(effects
				(font
					(size 0.7 0.7)
					(thickness 0.15)
				)
				(justify left bottom)
			)
		)
		(pad "1" smd roundrect
			(at -0.48 0 270)
			(size 0.59 0.64)
			(layers "F.Cu" "F.Mask" "F.Paste")
			(roundrect_rratio 0.25)
			(net 140 "/X710-AT2 Misc/NCSI.TXD_0")
			(pintype "passive")
		)
		(pad "2" smd roundrect
			(at 0.48 0 270)
			(size 0.59 0.64)
			(layers "F.Cu" "F.Mask" "F.Paste")
			(roundrect_rratio 0.25)
			(net 7 "+3V3")
			(pintype "passive")
		)
	)
)
